(kicad_pcb
	(version 20260206)
	(generator "pcbnew")
	(generator_version "10.0")
	(general
		(thickness 1.6)
		(legacy_teardrops no)
	)
	(paper "A4")
	(title_block
		(title "timecard-production-celestica-r4006 — R4006-B0001-02_R01.brd")
		(comment 1 "Time Appliance Project (Time Card) / footprints 355-357 of 1113")
	)
	(layers
		(0 "F.Cu" signal "TOP")
		(4 "In1.Cu" signal "L02_GND1")
		(6 "In2.Cu" signal "L03_SIG1")
		(8 "In3.Cu" signal "L04_GND2")
		(10 "In4.Cu" signal "L05_VCC1")
		(12 "In5.Cu" signal "L06_VCC2")
		(14 "In6.Cu" signal "L07_GND3")
		(16 "In7.Cu" signal "L08_SIG2")
		(18 "In8.Cu" signal "L09_GND4")
		(2 "B.Cu" signal "BOTTOM")
		(9 "F.Adhes" user "F.Adhesive")
		(11 "B.Adhes" user "B.Adhesive")
		(13 "F.Paste" user "Package Geometry/Pastemask Top")
		(15 "B.Paste" user "Package Geometry/Pastemask Bottom")
		(5 "F.SilkS" user "Ref Des/Silkscreen Top")
		(7 "B.SilkS" user "Ref Des/Silkscreen Bottom")
		(1 "F.Mask" user "Board Geometry/Soldermask Top")
		(3 "B.Mask" user "Board Geometry/Soldermask Bottom")
		(17 "Dwgs.User" user "User.Drawings")
		(19 "Cmts.User" user "User.Comments")
		(21 "Eco1.User" user "User.Eco1")
		(23 "Eco2.User" user "User.Eco2")
		(25 "Edge.Cuts" user "Board Geometry/Outline")
		(27 "Margin" user)
		(31 "F.CrtYd" user "Package Geometry/Place Bound Top")
		(29 "B.CrtYd" user "Package Geometry/Place Bound Bottom")
		(35 "F.Fab" user "Ref Des/Assembly Top")
		(33 "B.Fab" user "Ref Des/Assembly Bottom")
	)
	(footprint ""
		(layer "F.Cu")
		(at 84.2772 -97.2058 180)
		(property "Reference" "C48"
			(at 4.3942 -5.67817 0)
			(unlocked yes)
			(layer "F.SilkS")
			(effects
				(font
					(size 0.7874 0.5842)
					(thickness 0.1524)
				)
			)
		)
		(property "Value" "VAL*"
			(at 0.0762 3.134106 180)
			(unlocked yes)
			(layer "F.Fab")
			(hide yes)
			(effects
				(font
					(size 0.7874 0.5842)
					(thickness 0.1524)
				)
			)
		)
		(property "Tolerance" "TOL*"
			(at 0.0762 4.048506 180)
			(unlocked yes)
			(layer "Cmts.User")
			(hide yes)
			(effects
				(font
					(size 0.7874 0.5842)
					(thickness 0.1524)
				)
			)
		)
		(property "User Part Number" "PARTNUM*"
			(at 0.1016 5.013706 180)
			(unlocked yes)
			(layer "Cmts.User")
			(hide yes)
			(effects
				(font
					(size 0.7874 0.5842)
					(thickness 0.1524)
				)
			)
		)
		(property "Device Type" "CAPACITOR-G107-0F106-EM,10UF,2A"
			(at 0.0508 2.194306 180)
			(unlocked yes)
			(layer "F.Fab")
			(hide yes)
			(effects
				(font
					(size 0.7874 0.5842)
					(thickness 0.1524)
				)
			)
		)
		(duplicate_pad_numbers_are_jumpers no)
		(fp_line
			(start 1.5748 0.9398)
			(end 1.5748 -0.9398)
			(stroke
				(width 0.1)
				(type default)
			)
			(layer "F.SilkS")
		)
		(fp_line
			(start 1.5748 -0.9398)
			(end -1.5748 -0.9398)
			(stroke
				(width 0.1)
				(type default)
			)
			(layer "F.SilkS")
		)
		(fp_line
			(start -1.5748 0.9398)
			(end 1.5748 0.9398)
			(stroke
				(width 0.1)
				(type default)
			)
			(layer "F.SilkS")
		)
		(fp_line
			(start -1.5748 -0.9398)
			(end -1.5748 0.9398)
			(stroke
				(width 0.1)
				(type default)
			)
			(layer "F.SilkS")
		)
		(fp_rect
			(start 1.5748 -0.9398)
			(end -1.5748 0.9398)
			(stroke
				(width 0)
				(type default)
			)
			(fill no)
			(layer "F.CrtYd")
		)
		(fp_line
			(start 1.016 0.635)
			(end 1.016 -0.635)
			(stroke
				(width 0.1)
				(type default)
			)
			(layer "F.Fab")
		)
		(fp_line
			(start 1.016 -0.635)
			(end -1.016 -0.635)
			(stroke
				(width 0.1)
				(type default)
			)
			(layer "F.Fab")
		)
		(fp_line
			(start -1.016 0.635)
			(end 1.016 0.635)
			(stroke
				(width 0.1)
				(type default)
			)
			(layer "F.Fab")
		)
		(fp_line
			(start -1.016 -0.635)
			(end -1.016 0.635)
			(stroke
				(width 0.1)
				(type default)
			)
			(layer "F.Fab")
		)
		(pad "1" smd rect
			(at -0.8382 0 180)
			(size 0.9652 1.3716)
			(layers "F.Cu" "F.Mask" "F.Paste")
			(net "VIN_XP3R3")
		)
		(pad "2" smd rect
			(at 0.8382 0 180)
			(size 0.9652 1.3716)
			(layers "F.Cu" "F.Mask" "F.Paste")
			(net "SG")
		)
		(zone
			(layer "F.Cu")
			(hatch none 0.5)
			(connect_pads
				(clearance 0)
			)
			(min_thickness 0.25)
			(keepout
				(tracks allowed)
				(vias not_allowed)
				(pads allowed)
				(copperpour not_allowed)
				(footprints allowed)
			)
			(placement
				(enabled no)
				(sheetname "")
			)
			(fill
				(thermal_gap 0.5)
				(thermal_bridge_width 0.5)
				(island_removal_mode 0)
			)
			(polygon
				(pts
					(xy 84.0486 -96.5708) (xy 84.5058 -96.5708) (xy 84.5058 -97.8408) (xy 84.0486 -97.8408)
				)
			)
		)
	)
	(footprint ""
		(layer "F.Cu")
		(at 155.4734 -71.501 90)
		(property "Reference" "J10"
			(at 7.07263 0.2286 0)
			(unlocked yes)
			(layer "F.SilkS")
			(effects
				(font
					(size 0.7874 0.5842)
					(thickness 0.1524)
				)
			)
		)
		(property "Value" ""
			(at 0 0 90)
			(layer "F.Fab")
			(effects
				(font
					(size 1.27 1.27)
				)
			)
		)
		(property "User Part Number" "PARTNUM*"
			(at 0.191262 6.403086 90)
			(unlocked yes)
			(layer "Cmts.User")
			(hide yes)
			(effects
				(font
					(size 0.7874 0.5842)
					(thickness 0.1524)
				)
			)
		)
		(property "Device Type" "G200_10283_01-G200-10283-01"
			(at 0.241808 5.437378 90)
			(unlocked yes)
			(layer "F.Fab")
			(hide yes)
			(effects
				(font
					(size 0.7874 0.5842)
					(thickness 0.1524)
				)
			)
		)
		(duplicate_pad_numbers_are_jumpers no)
		(fp_line
			(start 6.4008 -4.6355)
			(end 6.4008 4.6355)
			(stroke
				(width 0.1)
				(type default)
			)
			(layer "F.SilkS")
		)
		(fp_line
			(start -6.4008 -4.6355)
			(end 6.4008 -4.6355)
			(stroke
				(width 0.1)
				(type default)
			)
			(layer "F.SilkS")
		)
		(fp_line
			(start 6.4008 4.6355)
			(end -6.4008 4.6355)
			(stroke
				(width 0.1)
				(type default)
			)
			(layer "F.SilkS")
		)
		(fp_line
			(start -6.4008 4.6355)
			(end -6.4008 -4.6355)
			(stroke
				(width 0.1)
				(type default)
			)
			(layer "F.SilkS")
		)
		(fp_rect
			(start -6.6548 4.8895)
			(end 6.6548 -4.8895)
			(stroke
				(width 0)
				(type default)
			)
			(fill no)
			(layer "F.CrtYd")
		)
		(fp_line
			(start 5.386832 -3.7084)
			(end 5.386832 -2.436876)
			(stroke
				(width 0.1)
				(type default)
			)
			(layer "F.Fab")
		)
		(fp_line
			(start 4.746752 -3.7084)
			(end 5.386832 -3.7084)
			(stroke
				(width 0.1)
				(type default)
			)
			(layer "F.Fab")
		)
		(fp_line
			(start 2.872232 -3.7084)
			(end 2.872232 -2.436876)
			(stroke
				(width 0.1)
				(type default)
			)
			(layer "F.Fab")
		)
		(fp_line
			(start 2.232152 -3.7084)
			(end 2.872232 -3.7084)
			(stroke
				(width 0.1)
				(type default)
			)
			(layer "F.Fab")
		)
		(fp_line
			(start 0.306832 -3.7084)
			(end 0.306832 -2.436876)
			(stroke
				(width 0.1)
				(type default)
			)
			(layer "F.Fab")
		)
		(fp_line
			(start -0.333248 -3.7084)
			(end 0.306832 -3.7084)
			(stroke
				(width 0.1)
				(type default)
			)
			(layer "F.Fab")
		)
		(fp_line
			(start -2.233168 -3.7084)
			(end -2.233168 -2.436876)
			(stroke
				(width 0.1)
				(type default)
			)
			(layer "F.Fab")
		)
		(fp_line
			(start -2.873248 -3.7084)
			(end -2.233168 -3.7084)
			(stroke
				(width 0.1)
				(type default)
			)
			(layer "F.Fab")
		)
		(fp_line
			(start -4.773168 -3.7084)
			(end -4.773168 -2.436876)
			(stroke
				(width 0.1)
				(type default)
			)
			(layer "F.Fab")
		)
		(fp_line
			(start -5.413248 -3.7084)
			(end -4.773168 -3.7084)
			(stroke
				(width 0.1)
				(type default)
			)
			(layer "F.Fab")
		)
		(fp_line
			(start 6.145022 -2.4384)
			(end 6.145022 2.4384)
			(stroke
				(width 0.1)
				(type default)
			)
			(layer "F.Fab")
		)
		(fp_line
			(start -6.145022 -2.4384)
			(end 6.145022 -2.4384)
			(stroke
				(width 0.1)
				(type default)
			)
			(layer "F.Fab")
		)
		(fp_line
			(start 5.386832 -2.436876)
			(end 4.746752 -2.436876)
			(stroke
				(width 0.1)
				(type default)
			)
			(layer "F.Fab")
		)
		(fp_line
			(start 4.746752 -2.436876)
			(end 4.746752 -3.7084)
			(stroke
				(width 0.1)
				(type default)
			)
			(layer "F.Fab")
		)
		(fp_line
			(start 2.872232 -2.436876)
			(end 2.232152 -2.436876)
			(stroke
				(width 0.1)
				(type default)
			)
			(layer "F.Fab")
		)
		(fp_line
			(start 2.232152 -2.436876)
			(end 2.232152 -3.7084)
			(stroke
				(width 0.1)
				(type default)
			)
			(layer "F.Fab")
		)
		(fp_line
			(start 0.306832 -2.436876)
			(end -0.333248 -2.436876)
			(stroke
				(width 0.1)
				(type default)
			)
			(layer "F.Fab")
		)
		(fp_line
			(start -0.333248 -2.436876)
			(end -0.333248 -3.7084)
			(stroke
				(width 0.1)
				(type default)
			)
			(layer "F.Fab")
		)
		(fp_line
			(start -2.233168 -2.436876)
			(end -2.873248 -2.436876)
			(stroke
				(width 0.1)
				(type default)
			)
			(layer "F.Fab")
		)
		(fp_line
			(start -2.873248 -2.436876)
			(end -2.873248 -3.7084)
			(stroke
				(width 0.1)
				(type default)
			)
			(layer "F.Fab")
		)
		(fp_line
			(start -4.773168 -2.436876)
			(end -5.413248 -2.436876)
			(stroke
				(width 0.1)
				(type default)
			)
			(layer "F.Fab")
		)
		(fp_line
			(start -5.413248 -2.436876)
			(end -5.413248 -3.7084)
			(stroke
				(width 0.1)
				(type default)
			)
			(layer "F.Fab")
		)
		(fp_line
			(start 6.145022 2.4384)
			(end -6.145022 2.4384)
			(stroke
				(width 0.1)
				(type default)
			)
			(layer "F.Fab")
		)
		(fp_line
			(start 5.386832 2.4384)
			(end 5.386832 3.709924)
			(stroke
				(width 0.1)
				(type default)
			)
			(layer "F.Fab")
		)
		(fp_line
			(start 4.746752 2.4384)
			(end 5.386832 2.4384)
			(stroke
				(width 0.1)
				(type default)
			)
			(layer "F.Fab")
		)
		(fp_line
			(start 2.846832 2.4384)
			(end 2.846832 3.709924)
			(stroke
				(width 0.1)
				(type default)
			)
			(layer "F.Fab")
		)
		(fp_line
			(start 2.206752 2.4384)
			(end 2.846832 2.4384)
			(stroke
				(width 0.1)
				(type default)
			)
			(layer "F.Fab")
		)
		(fp_line
			(start 0.306832 2.4384)
			(end 0.306832 3.709924)
			(stroke
				(width 0.1)
				(type default)
			)
			(layer "F.Fab")
		)
		(fp_line
			(start -0.333248 2.4384)
			(end 0.306832 2.4384)
			(stroke
				(width 0.1)
				(type default)
			)
			(layer "F.Fab")
		)
		(fp_line
			(start -2.233168 2.4384)
			(end -2.233168 3.709924)
			(stroke
				(width 0.1)
				(type default)
			)
			(layer "F.Fab")
		)
		(fp_line
			(start -2.873248 2.4384)
			(end -2.233168 2.4384)
			(stroke
				(width 0.1)
				(type default)
			)
			(layer "F.Fab")
		)
		(fp_line
			(start -4.747768 2.4384)
			(end -4.747768 3.709924)
			(stroke
				(width 0.1)
				(type default)
			)
			(layer "F.Fab")
		)
		(fp_line
			(start -5.387848 2.4384)
			(end -4.747768 2.4384)
			(stroke
				(width 0.1)
				(type default)
			)
			(layer "F.Fab")
		)
		(fp_line
			(start -6.145022 2.4384)
			(end -6.145022 -2.4384)
			(stroke
				(width 0.1)
				(type default)
			)
			(layer "F.Fab")
		)
		(fp_line
			(start 5.386832 3.709924)
			(end 4.746752 3.709924)
			(stroke
				(width 0.1)
				(type default)
			)
			(layer "F.Fab")
		)
		(fp_line
			(start 4.746752 3.709924)
			(end 4.746752 2.4384)
			(stroke
				(width 0.1)
				(type default)
			)
			(layer "F.Fab")
		)
		(fp_line
			(start 2.846832 3.709924)
			(end 2.206752 3.709924)
			(stroke
				(width 0.1)
				(type default)
			)
			(layer "F.Fab")
		)
		(fp_line
			(start 2.206752 3.709924)
			(end 2.206752 2.4384)
			(stroke
				(width 0.1)
				(type default)
			)
			(layer "F.Fab")
		)
		(fp_line
			(start 0.306832 3.709924)
			(end -0.333248 3.709924)
			(stroke
				(width 0.1)
				(type default)
			)
			(layer "F.Fab")
		)
		(fp_line
			(start -0.333248 3.709924)
			(end -0.333248 2.4384)
			(stroke
				(width 0.1)
				(type default)
			)
			(layer "F.Fab")
		)
		(fp_line
			(start -2.233168 3.709924)
			(end -2.873248 3.709924)
			(stroke
				(width 0.1)
				(type default)
			)
			(layer "F.Fab")
		)
		(fp_line
			(start -2.873248 3.709924)
			(end -2.873248 2.4384)
			(stroke
				(width 0.1)
				(type default)
			)
			(layer "F.Fab")
		)
		(fp_line
			(start -4.747768 3.709924)
			(end -5.387848 3.709924)
			(stroke
				(width 0.1)
				(type default)
			)
			(layer "F.Fab")
		)
		(fp_line
			(start -5.387848 3.709924)
			(end -5.387848 2.4384)
			(stroke
				(width 0.1)
				(type default)
			)
			(layer "F.Fab")
		)
		(fp_text user "10"
			(at 6.223 -5.57403 90)
			(unlocked yes)
			(layer "F.SilkS")
			(effects
				(font
					(size 0.7874 0.5842)
					(thickness 0.1524)
				)
			)
		)
		(fp_text user "2"
			(at -5.88137 -5.2324 0)
			(unlocked yes)
			(layer "F.SilkS")
			(effects
				(font
					(size 0.7874 0.5842)
					(thickness 0.1524)
				)
			)
		)
		(fp_text user "1"
			(at -5.37337 5.3086 0)
			(unlocked yes)
			(layer "F.SilkS")
			(effects
				(font
					(size 0.7874 0.5842)
					(thickness 0.1524)
				)
			)
		)
		(fp_text user "9"
			(at 6.05663 5.4356 0)
			(unlocked yes)
			(layer "F.SilkS")
			(effects
				(font
					(size 0.7874 0.5842)
					(thickness 0.1524)
				)
			)
		)
		(fp_text user "10"
			(at 5.18033 -5.2324 0)
			(unlocked yes)
			(layer "F.Fab")
			(effects
				(font
					(size 0.7874 0.5842)
					(thickness 0.1524)
				)
			)
		)
		(fp_text user "2"
			(at -5.37337 -4.8514 0)
			(unlocked yes)
			(layer "F.Fab")
			(effects
				(font
					(size 0.7874 0.5842)
					(thickness 0.1524)
				)
			)
		)
		(fp_text user "9"
			(at 5.16763 5.0546 0)
			(unlocked yes)
			(layer "F.Fab")
			(effects
				(font
					(size 0.7874 0.5842)
					(thickness 0.1524)
				)
			)
		)
		(fp_text user "1"
			(at -5.37337 5.0546 0)
			(unlocked yes)
			(layer "F.Fab")
			(effects
				(font
					(size 0.7874 0.5842)
					(thickness 0.1524)
				)
			)
		)
		(pad "1" smd rect
			(at -5.08 2.605024 90)
			(size 1.27 3.556)
			(layers "F.Cu" "F.Mask" "F.Paste")
			(net "FT4232_CHD_TX")
		)
		(pad "2" smd rect
			(at -5.08 -2.605024 90)
			(size 1.27 3.556)
			(layers "F.Cu" "F.Mask" "F.Paste")
			(net "DBG_UART_MAC_RX")
		)
		(pad "3" smd rect
			(at -2.54 2.605024 90)
			(size 1.27 3.556)
			(layers "F.Cu" "F.Mask" "F.Paste")
			(net "FT4232_CHD_TX")
		)
		(pad "4" smd rect
			(at -2.54 -2.605024 90)
			(size 1.27 3.556)
			(layers "F.Cu" "F.Mask" "F.Paste")
			(net "DBG_UART_GPS_RXD")
		)
		(pad "5" smd rect
			(at 0 2.605024 90)
			(size 1.27 3.556)
			(layers "F.Cu" "F.Mask" "F.Paste")
			(net "FT4232_CHD_RX")
		)
		(pad "6" smd rect
			(at 0 -2.605024 90)
			(size 1.27 3.556)
			(layers "F.Cu" "F.Mask" "F.Paste")
			(net "DBG_UART_MAC_TX")
		)
		(pad "7" smd rect
			(at 2.54 2.605024 90)
			(size 1.27 3.556)
			(layers "F.Cu" "F.Mask" "F.Paste")
			(net "FT4232_CHD_RX")
		)
		(pad "8" smd rect
			(at 2.54 -2.605024 90)
			(size 1.27 3.556)
			(layers "F.Cu" "F.Mask" "F.Paste")
			(net "DBG_UART_GPS_TXD")
		)
		(pad "9" smd rect
			(at 5.08 2.605024 90)
			(size 1.27 3.556)
			(layers "F.Cu" "F.Mask" "F.Paste")
			(net "SG")
		)
		(pad "10" smd rect
			(at 5.08 -2.605024 90)
			(size 1.27 3.556)
			(layers "F.Cu" "F.Mask" "F.Paste")
			(net "FPGA_CFG_INIT_N")
		)
		(zone
			(layer "F.Cu")
			(hatch none 0.5)
			(connect_pads
				(clearance 0)
			)
			(min_thickness 0.25)
			(keepout
				(tracks not_allowed)
				(vias allowed)
				(pads allowed)
				(copperpour not_allowed)
				(footprints allowed)
			)
			(placement
				(enabled no)
				(sheetname "")
			)
			(fill
				(thermal_gap 0.5)
				(thermal_bridge_width 0.5)
				(island_removal_mode 0)
			)
			(polygon
				(pts
					(xy 156.2862 -65.789302) (xy 156.2862 -77.219302) (xy 154.6606 -77.219302) (xy 154.6606 -65.789302)
				)
			)
		)
		(zone
			(layer "F.Cu")
			(hatch none 0.5)
			(connect_pads
				(clearance 0)
			)
			(min_thickness 0.25)
			(keepout
				(tracks allowed)
				(vias not_allowed)
				(pads allowed)
				(copperpour not_allowed)
				(footprints allowed)
			)
			(placement
				(enabled no)
				(sheetname "")
			)
			(fill
				(thermal_gap 0.5)
				(thermal_bridge_width 0.5)
				(island_removal_mode 0)
			)
			(polygon
				(pts
					(xy 156.2862 -65.789302) (xy 156.2862 -77.219302) (xy 154.6606 -77.219302) (xy 154.6606 -65.789302)
				)
			)
		)
	)
	(footprint ""
		(layer "F.Cu")
		(at 111.887 -96.266)
		(property "Reference" "C89"
			(at 2.794 0.16637 0)
			(unlocked yes)
			(layer "F.SilkS")
			(effects
				(font
					(size 0.7874 0.5842)
					(thickness 0.1524)
				)
			)
		)
		(property "Value" "VAL*"
			(at 0.0762 2.067306 0)
			(unlocked yes)
			(layer "F.Fab")
			(hide yes)
			(effects
				(font
					(size 0.7874 0.5842)
					(thickness 0.1524)
				)
			)
		)
		(property "Tolerance" "TOL*"
			(at 0.0762 3.032506 0)
			(unlocked yes)
			(layer "Cmts.User")
			(hide yes)
			(effects
				(font
					(size 0.7874 0.5842)
					(thickness 0.1524)
				)
			)
		)
		(property "User Part Number" "PARTNUM*"
			(at 0.1016 4.023106 0)
			(unlocked yes)
			(layer "Cmts.User")
			(hide yes)
			(effects
				(font
					(size 0.7874 0.5842)
					(thickness 0.1524)
				)
			)
		)
		(property "Device Type" "CAPACITOR-G105-0B104-EK,0.1UF,A"
			(at 0.0508 1.127506 0)
			(unlocked yes)
			(layer "F.Fab")
			(hide yes)
			(effects
				(font
					(size 0.7874 0.5842)
					(thickness 0.1524)
				)
			)
		)
		(duplicate_pad_numbers_are_jumpers no)
		(fp_line
			(start -1.143 -0.5588)
			(end -1.143 0.5588)
			(stroke
				(width 0.1)
				(type default)
			)
			(layer "F.SilkS")
		)
		(fp_line
			(start -1.143 0.5588)
			(end 1.143 0.5588)
			(stroke
				(width 0.1)
				(type default)
			)
			(layer "F.SilkS")
		)
		(fp_line
			(start 1.143 -0.5588)
			(end -1.143 -0.5588)
			(stroke
				(width 0.1)
				(type default)
			)
			(layer "F.SilkS")
		)
		(fp_line
			(start 1.143 0.5588)
			(end 1.143 -0.5588)
			(stroke
				(width 0.1)
				(type default)
			)
			(layer "F.SilkS")
		)
		(fp_rect
			(start 1.143 -0.5588)
			(end -1.143 0.5588)
			(stroke
				(width 0)
				(type default)
			)
			(fill no)
			(layer "F.CrtYd")
		)
		(fp_line
			(start -0.508 -0.3048)
			(end -0.508 0.3048)
			(stroke
				(width 0.1)
				(type default)
			)
			(layer "F.Fab")
		)
		(fp_line
			(start -0.508 0.3048)
			(end 0.508 0.3048)
			(stroke
				(width 0.1)
				(type default)
			)
			(layer "F.Fab")
		)
		(fp_line
			(start 0.508 -0.3048)
			(end -0.508 -0.3048)
			(stroke
				(width 0.1)
				(type default)
			)
			(layer "F.Fab")
		)
		(fp_line
			(start 0.508 0.3048)
			(end 0.508 -0.3048)
			(stroke
				(width 0.1)
				(type default)
			)
			(layer "F.Fab")
		)
		(pad "1" smd rect
			(at -0.5334 0)
			(size 0.7112 0.6096)
			(layers "F.Cu" "F.Mask" "F.Paste")
			(net "XP3R3V_FPGA")
		)
		(pad "2" smd rect
			(at 0.5334 0)
			(size 0.7112 0.6096)
			(layers "F.Cu" "F.Mask" "F.Paste")
			(net "SG")
		)
		(zone
			(layer "F.Cu")
			(hatch none 0.5)
			(connect_pads
				(clearance 0)
			)
			(min_thickness 0.25)
			(keepout
				(tracks allowed)
				(vias not_allowed)
				(pads allowed)
				(copperpour not_allowed)
				(footprints allowed)
			)
			(placement
				(enabled no)
				(sheetname "")
			)
			(fill
				(thermal_gap 0.5)
				(thermal_bridge_width 0.5)
				(island_removal_mode 0)
			)
			(polygon
				(pts
					(xy 111.9632 -96.5708) (xy 111.8108 -96.5708) (xy 111.8108 -95.9612) (xy 111.9632 -95.9612)
				)
			)
		)
	)
)
